(kicad_pcb
	(version 20260206)
	(generator "pcbnew")
	(generator_version "10.0")
	(general
		(thickness 1.6)
		(legacy_teardrops no)
	)
	(paper "A4")
	(title_block
		(title "Bryce Canyon_SCC_16316-1_OCP.brd")
		(comment 1 "Bryce Canyon / footprints 1190-1196 of 1561")
	)
	(layers
		(0 "F.Cu" signal "TOP")
		(4 "In1.Cu" signal "L2GND")
		(6 "In2.Cu" signal "L3")
		(8 "In3.Cu" signal "L4VCC")
		(10 "In4.Cu" signal "L5VCC")
		(12 "In5.Cu" signal "L6")
		(14 "In6.Cu" signal "L7GND")
		(2 "B.Cu" signal "BOTTOM")
		(9 "F.Adhes" user "F.Adhesive")
		(11 "B.Adhes" user "B.Adhesive")
		(13 "F.Paste" user "Package Geometry/Pastemask Top")
		(15 "B.Paste" user "Package Geometry/Pastemask Bottom")
		(5 "F.SilkS" user "Ref Des/Silkscreen Top")
		(7 "B.SilkS" user "Ref Des/Silkscreen Bottom")
		(1 "F.Mask" user "Board Geometry/Soldermask Top")
		(3 "B.Mask" user "Board Geometry/Soldermask Bottom")
		(17 "Dwgs.User" user "User.Drawings")
		(19 "Cmts.User" user "User.Comments")
		(21 "Eco1.User" user "User.Eco1")
		(23 "Eco2.User" user "User.Eco2")
		(25 "Edge.Cuts" user "Board Geometry/Outline")
		(27 "Margin" user)
		(31 "F.CrtYd" user "Package Geometry/Place Bound Top")
		(29 "B.CrtYd" user "Package Geometry/Place Bound Bottom")
		(35 "F.Fab" user "Ref Des/Assembly Top")
		(33 "B.Fab" user "Ref Des/Assembly Bottom")
	)
	(footprint ""
		(layer "B.Cu")
		(at 169.5577 -21.004276)
		(property "Reference" "C316"
			(at 0 0 0)
			(layer "B.SilkS")
			(hide yes)
			(effects
				(font
					(size 1.27 1.27)
				)
				(justify mirror)
			)
		)
		(property "Value" "SCD22U10V1KX-GP"
			(at 2.8321 -1.7399 0)
			(unlocked yes)
			(layer "B.Fab")
			(hide yes)
			(effects
				(font
					(size 1.016 1.016)
					(thickness 0.1524)
				)
				(justify mirror)
			)
		)
		(property "Device Type" "C0201H13"
			(at 2.8321 -3.2639 0)
			(unlocked yes)
			(layer "B.Fab")
			(hide yes)
			(effects
				(font
					(size 1.016 1.016)
					(thickness 0.1524)
				)
				(justify mirror)
			)
		)
		(duplicate_pad_numbers_are_jumpers no)
		(fp_rect
			(start 0.2794 0.6477)
			(end -0.2794 -0.6477)
			(stroke
				(width 0)
				(type default)
			)
			(fill no)
			(layer "B.CrtYd")
		)
		(fp_rect
			(start 0.2794 0.6477)
			(end -0.2794 -0.6477)
			(stroke
				(width 0)
				(type default)
			)
			(fill no)
			(layer "B.Fab")
		)
		(pad "1" smd custom
			(at 0 -0.2794 180)
			(size 0.0762 0.0762)
			(layers "B.Cu" "B.Mask" "B.Paste")
			(net "PCIE_SCC_TO_COMP_C_2_DN")
			(options
				(clearance outline)
				(anchor circle)
			)
			(primitives
				(gr_poly
					(pts
						(arc
							(start 0.1524 0.127)
							(mid 0.137521 0.162921)
							(end 0.1016 0.1778)
						)
						(arc
							(start -0.1016 0.1778)
							(mid -0.137521 0.162921)
							(end -0.1524 0.127)
						)
						(arc
							(start -0.1524 -0.127)
							(mid -0.137521 -0.162921)
							(end -0.1016 -0.1778)
						)
						(arc
							(start 0.1016 -0.1778)
							(mid 0.137521 -0.162921)
							(end 0.1524 -0.127)
						)
					)
					(width 0)
					(fill yes)
				)
			)
		)
		(pad "2" smd custom
			(at 0 0.2794 180)
			(size 0.0762 0.0762)
			(layers "B.Cu" "B.Mask" "B.Paste")
			(net "PCIE_SCC_TO_COMP_2_DN")
			(options
				(clearance outline)
				(anchor circle)
			)
			(primitives
				(gr_poly
					(pts
						(arc
							(start 0.1524 0.127)
							(mid 0.137521 0.162921)
							(end 0.1016 0.1778)
						)
						(arc
							(start -0.1016 0.1778)
							(mid -0.137521 0.162921)
							(end -0.1524 0.127)
						)
						(arc
							(start -0.1524 -0.127)
							(mid -0.137521 -0.162921)
							(end -0.1016 -0.1778)
						)
						(arc
							(start 0.1016 -0.1778)
							(mid 0.137521 -0.162921)
							(end 0.1524 -0.127)
						)
					)
					(width 0)
					(fill yes)
				)
			)
		)
	)
	(footprint ""
		(layer "B.Cu")
		(at 139.168632 -84.691728)
		(property "Reference" "R49"
			(at 0 0 0)
			(layer "B.SilkS")
			(hide yes)
			(effects
				(font
					(size 1.27 1.27)
				)
				(justify mirror)
			)
		)
		(property "Value" "4K7R2F-GP"
			(at -0.064008 -3.993896 0)
			(unlocked yes)
			(layer "B.Fab")
			(hide yes)
			(effects
				(font
					(size 1.016 1.016)
					(thickness 0.1524)
				)
				(justify mirror)
			)
		)
		(property "Device Type" "R402H16"
			(at -0.064008 -5.517896 0)
			(unlocked yes)
			(layer "B.Fab")
			(hide yes)
			(effects
				(font
					(size 1.016 1.016)
					(thickness 0.1524)
				)
				(justify mirror)
			)
		)
		(duplicate_pad_numbers_are_jumpers no)
		(fp_line
			(start -0.508 -0.9398)
			(end 0.508 -0.9398)
			(stroke
				(width 0.1524)
				(type default)
			)
			(layer "B.SilkS")
		)
		(fp_line
			(start 0.508 -0.9398)
			(end 0.508 0.9398)
			(stroke
				(width 0.1524)
				(type default)
			)
			(layer "B.SilkS")
		)
		(fp_rect
			(start 0.508 0.9398)
			(end -0.508 -0.9398)
			(stroke
				(width 0)
				(type default)
			)
			(fill no)
			(layer "B.CrtYd")
		)
		(fp_rect
			(start 0.508 0.9398)
			(end -0.508 -0.9398)
			(stroke
				(width 0)
				(type default)
			)
			(fill no)
			(layer "B.Fab")
		)
		(pad "1" smd custom
			(at 0 -0.4445 180)
			(size 0.1397 0.1397)
			(layers "B.Cu" "B.Mask" "B.Paste")
			(net "P1V8_E")
			(options
				(clearance outline)
				(anchor circle)
			)
			(primitives
				(gr_poly
					(pts
						(arc
							(start -0.1778 0.2794)
							(mid -0.249642 0.249642)
							(end -0.2794 0.1778)
						)
						(arc
							(start -0.2794 -0.1778)
							(mid -0.249642 -0.249642)
							(end -0.1778 -0.2794)
						)
						(arc
							(start 0.1778 -0.2794)
							(mid 0.249642 -0.249642)
							(end 0.2794 -0.1778)
						)
						(arc
							(start 0.2794 0.1778)
							(mid 0.249642 0.249642)
							(end 0.1778 0.2794)
						)
					)
					(width 0)
					(fill yes)
				)
			)
		)
		(pad "2" smd custom
			(at 0 0.4445 180)
			(size 0.1397 0.1397)
			(layers "B.Cu" "B.Mask" "B.Paste")
			(net "I2C_BMC_LOC_SDA0_LS")
			(options
				(clearance outline)
				(anchor circle)
			)
			(primitives
				(gr_poly
					(pts
						(arc
							(start -0.1778 0.2794)
							(mid -0.249642 0.249642)
							(end -0.2794 0.1778)
						)
						(arc
							(start -0.2794 -0.1778)
							(mid -0.249642 -0.249642)
							(end -0.1778 -0.2794)
						)
						(arc
							(start 0.1778 -0.2794)
							(mid 0.249642 -0.249642)
							(end 0.2794 -0.1778)
						)
						(arc
							(start 0.2794 0.1778)
							(mid 0.249642 0.249642)
							(end 0.1778 0.2794)
						)
					)
					(width 0)
					(fill yes)
				)
			)
		)
	)
	(footprint ""
		(layer "B.Cu")
		(at 92.168472 -67.625214 180)
		(property "Reference" "C200"
			(at 0 0 0)
			(layer "B.SilkS")
			(hide yes)
			(effects
				(font
					(size 1.27 1.27)
				)
				(justify mirror)
			)
		)
		(property "Value" "SC22U6D3V3MX-9-GP-U"
			(at 0 -2.8194 180)
			(unlocked yes)
			(layer "B.Fab")
			(hide yes)
			(effects
				(font
					(size 1.016 1.016)
					(thickness 0.1524)
				)
				(justify mirror)
			)
		)
		(property "Device Type" "C603H40"
			(at 0 -4.3434 180)
			(unlocked yes)
			(layer "B.Fab")
			(hide yes)
			(effects
				(font
					(size 1.016 1.016)
					(thickness 0.1524)
				)
				(justify mirror)
			)
		)
		(duplicate_pad_numbers_are_jumpers no)
		(fp_line
			(start -0.508 0)
			(end 0.508 0)
			(stroke
				(width 0.2032)
				(type default)
			)
			(layer "B.SilkS")
		)
		(fp_rect
			(start 0.5842 1.3335)
			(end -0.5842 -1.3335)
			(stroke
				(width 0)
				(type default)
			)
			(fill no)
			(layer "B.CrtYd")
		)
		(fp_rect
			(start 0.5842 1.3335)
			(end -0.5842 -1.3335)
			(stroke
				(width 0)
				(type default)
			)
			(fill no)
			(layer "B.Fab")
		)
		(pad "1" smd custom
			(at 0 -0.762)
			(size 0.2159 0.2159)
			(layers "B.Cu" "B.Mask" "B.Paste")
			(net "PLLDDR_VDDA18")
			(options
				(clearance outline)
				(anchor circle)
			)
			(primitives
				(gr_poly
					(pts
						(arc
							(start -0.3302 0.4318)
							(mid -0.402042 0.402042)
							(end -0.4318 0.3302)
						)
						(arc
							(start -0.4318 -0.3302)
							(mid -0.402042 -0.402042)
							(end -0.3302 -0.4318)
						)
						(arc
							(start 0.3302 -0.4318)
							(mid 0.402042 -0.402042)
							(end 0.4318 -0.3302)
						)
						(arc
							(start 0.4318 0.3302)
							(mid 0.402042 0.402042)
							(end 0.3302 0.4318)
						)
					)
					(width 0)
					(fill yes)
				)
			)
		)
		(pad "2" smd custom
			(at 0 0.762)
			(size 0.2159 0.2159)
			(layers "B.Cu" "B.Mask" "B.Paste")
			(net "GND")
			(options
				(clearance outline)
				(anchor circle)
			)
			(primitives
				(gr_poly
					(pts
						(arc
							(start -0.3302 0.4318)
							(mid -0.402042 0.402042)
							(end -0.4318 0.3302)
						)
						(arc
							(start -0.4318 -0.3302)
							(mid -0.402042 -0.402042)
							(end -0.3302 -0.4318)
						)
						(arc
							(start 0.3302 -0.4318)
							(mid 0.402042 -0.402042)
							(end 0.4318 -0.3302)
						)
						(arc
							(start 0.4318 0.3302)
							(mid 0.402042 0.402042)
							(end 0.3302 0.4318)
						)
					)
					(width 0)
					(fill yes)
				)
			)
		)
	)
	(footprint ""
		(layer "B.Cu")
		(at 162.56 -52.07)
		(property "Reference" "R204"
			(at 0 0 0)
			(layer "B.SilkS")
			(hide yes)
			(effects
				(font
					(size 1.27 1.27)
				)
				(justify mirror)
			)
		)
		(property "Value" "2K2R2F-GP"
			(at -0.064008 -3.993896 0)
			(unlocked yes)
			(layer "B.Fab")
			(hide yes)
			(effects
				(font
					(size 1.016 1.016)
					(thickness 0.1524)
				)
				(justify mirror)
			)
		)
		(property "Device Type" "R402H16"
			(at -0.064008 -5.517896 0)
			(unlocked yes)
			(layer "B.Fab")
			(hide yes)
			(effects
				(font
					(size 1.016 1.016)
					(thickness 0.1524)
				)
				(justify mirror)
			)
		)
		(duplicate_pad_numbers_are_jumpers no)
		(fp_line
			(start -0.508 -0.9398)
			(end 0.508 -0.9398)
			(stroke
				(width 0.1524)
				(type default)
			)
			(layer "B.SilkS")
		)
		(fp_line
			(start 0.508 -0.9398)
			(end 0.508 0.9398)
			(stroke
				(width 0.1524)
				(type default)
			)
			(layer "B.SilkS")
		)
		(fp_rect
			(start 0.508 0.9398)
			(end -0.508 -0.9398)
			(stroke
				(width 0)
				(type default)
			)
			(fill no)
			(layer "B.CrtYd")
		)
		(fp_rect
			(start 0.508 0.9398)
			(end -0.508 -0.9398)
			(stroke
				(width 0)
				(type default)
			)
			(fill no)
			(layer "B.Fab")
		)
		(pad "1" smd custom
			(at 0 -0.4445 180)
			(size 0.1397 0.1397)
			(layers "B.Cu" "B.Mask" "B.Paste")
			(net "P1V8_C")
			(options
				(clearance outline)
				(anchor circle)
			)
			(primitives
				(gr_poly
					(pts
						(arc
							(start -0.1778 0.2794)
							(mid -0.249642 0.249642)
							(end -0.2794 0.1778)
						)
						(arc
							(start -0.2794 -0.1778)
							(mid -0.249642 -0.249642)
							(end -0.1778 -0.2794)
						)
						(arc
							(start 0.1778 -0.2794)
							(mid 0.249642 -0.249642)
							(end 0.2794 -0.1778)
						)
						(arc
							(start 0.2794 0.1778)
							(mid 0.249642 0.249642)
							(end 0.1778 0.2794)
						)
					)
					(width 0)
					(fill yes)
				)
			)
		)
		(pad "2" smd custom
			(at 0 0.4445 180)
			(size 0.1397 0.1397)
			(layers "B.Cu" "B.Mask" "B.Paste")
			(net "SIO_LOAD_1")
			(options
				(clearance outline)
				(anchor circle)
			)
			(primitives
				(gr_poly
					(pts
						(arc
							(start -0.1778 0.2794)
							(mid -0.249642 0.249642)
							(end -0.2794 0.1778)
						)
						(arc
							(start -0.2794 -0.1778)
							(mid -0.249642 -0.249642)
							(end -0.1778 -0.2794)
						)
						(arc
							(start 0.1778 -0.2794)
							(mid 0.249642 -0.249642)
							(end 0.2794 -0.1778)
						)
						(arc
							(start 0.2794 0.1778)
							(mid 0.249642 0.249642)
							(end 0.1778 0.2794)
						)
					)
					(width 0)
					(fill yes)
				)
			)
		)
	)
	(footprint ""
		(layer "B.Cu")
		(at 76.454 -57.404)
		(property "Reference" "C249"
			(at 0 0 0)
			(layer "B.SilkS")
			(hide yes)
			(effects
				(font
					(size 1.27 1.27)
				)
				(justify mirror)
			)
		)
		(property "Value" "SC22U6D3V3MX-9-GP-U"
			(at 0 -2.8194 0)
			(unlocked yes)
			(layer "B.Fab")
			(hide yes)
			(effects
				(font
					(size 1.016 1.016)
					(thickness 0.1524)
				)
				(justify mirror)
			)
		)
		(property "Device Type" "C603H40"
			(at 0 -4.3434 0)
			(unlocked yes)
			(layer "B.Fab")
			(hide yes)
			(effects
				(font
					(size 1.016 1.016)
					(thickness 0.1524)
				)
				(justify mirror)
			)
		)
		(duplicate_pad_numbers_are_jumpers no)
		(fp_line
			(start -0.508 0)
			(end 0.508 0)
			(stroke
				(width 0.2032)
				(type default)
			)
			(layer "B.SilkS")
		)
		(fp_rect
			(start 0.5842 1.3335)
			(end -0.5842 -1.3335)
			(stroke
				(width 0)
				(type default)
			)
			(fill no)
			(layer "B.CrtYd")
		)
		(fp_rect
			(start 0.5842 1.3335)
			(end -0.5842 -1.3335)
			(stroke
				(width 0)
				(type default)
			)
			(fill no)
			(layer "B.Fab")
		)
		(pad "1" smd custom
			(at 0 -0.762 180)
			(size 0.2159 0.2159)
			(layers "B.Cu" "B.Mask" "B.Paste")
			(net "GB_VDDA")
			(options
				(clearance outline)
				(anchor circle)
			)
			(primitives
				(gr_poly
					(pts
						(arc
							(start -0.3302 0.4318)
							(mid -0.402042 0.402042)
							(end -0.4318 0.3302)
						)
						(arc
							(start -0.4318 -0.3302)
							(mid -0.402042 -0.402042)
							(end -0.3302 -0.4318)
						)
						(arc
							(start 0.3302 -0.4318)
							(mid 0.402042 -0.402042)
							(end 0.4318 -0.3302)
						)
						(arc
							(start 0.4318 0.3302)
							(mid 0.402042 0.402042)
							(end 0.3302 0.4318)
						)
					)
					(width 0)
					(fill yes)
				)
			)
		)
		(pad "2" smd custom
			(at 0 0.762 180)
			(size 0.2159 0.2159)
			(layers "B.Cu" "B.Mask" "B.Paste")
			(net "GND")
			(options
				(clearance outline)
				(anchor circle)
			)
			(primitives
				(gr_poly
					(pts
						(arc
							(start -0.3302 0.4318)
							(mid -0.402042 0.402042)
							(end -0.4318 0.3302)
						)
						(arc
							(start -0.4318 -0.3302)
							(mid -0.402042 -0.402042)
							(end -0.3302 -0.4318)
						)
						(arc
							(start 0.3302 -0.4318)
							(mid 0.402042 -0.402042)
							(end 0.4318 -0.3302)
						)
						(arc
							(start 0.4318 0.3302)
							(mid 0.402042 0.402042)
							(end 0.3302 0.4318)
						)
					)
					(width 0)
					(fill yes)
				)
			)
		)
	)
	(footprint ""
		(layer "B.Cu")
		(at 124.4981 -53.5051 90)
		(property "Reference" "C281"
			(at 0 0 90)
			(layer "B.SilkS")
			(hide yes)
			(effects
				(font
					(size 1.27 1.27)
				)
				(justify mirror)
			)
		)
		(property "Value" "SC1U6D3V1MX-GP"
			(at -1.9177 2.0193 90)
			(unlocked yes)
			(layer "B.Fab")
			(hide yes)
			(effects
				(font
					(size 1.016 1.016)
					(thickness 0.1524)
				)
				(justify mirror)
			)
		)
		(property "Device Type" "C0201H14"
			(at -1.9177 0.4953 90)
			(unlocked yes)
			(layer "B.Fab")
			(hide yes)
			(effects
				(font
					(size 1.016 1.016)
					(thickness 0.1524)
				)
				(justify mirror)
			)
		)
		(duplicate_pad_numbers_are_jumpers no)
		(fp_rect
			(start 0.1524 0.3048)
			(end -0.1524 -0.3048)
			(stroke
				(width 0)
				(type default)
			)
			(fill no)
			(layer "B.CrtYd")
		)
		(fp_poly
			(pts
				(xy 0.2794 0.6477) (xy 0.2794 -0.6477) (xy -0.2794 -0.6477) (xy -0.2794 -0.1905) (xy -0.1524 -0.1905)
				(xy -0.1524 -0.3048) (xy 0.1524 -0.3048) (xy 0.1524 0.3048) (xy -0.1524 0.3048) (xy -0.1524 -0.1778)
				(xy -0.2794 -0.1778) (xy -0.2794 0.6477)
			)
			(stroke
				(width 0)
				(type default)
			)
			(fill no)
			(layer "B.CrtYd")
		)
		(fp_rect
			(start 0.2794 0.6477)
			(end -0.2794 -0.6477)
			(stroke
				(width 0)
				(type default)
			)
			(fill no)
			(layer "B.Fab")
		)
		(pad "1" smd custom
			(at 0 -0.2794 270)
			(size 0.0762 0.0762)
			(layers "B.Cu" "B.Mask" "B.Paste")
			(net "GB_VDDA")
			(options
				(clearance outline)
				(anchor circle)
			)
			(primitives
				(gr_poly
					(pts
						(arc
							(start 0.1524 0.127)
							(mid 0.137521 0.162921)
							(end 0.1016 0.1778)
						)
						(arc
							(start -0.1016 0.1778)
							(mid -0.137521 0.162921)
							(end -0.1524 0.127)
						)
						(arc
							(start -0.1524 -0.127)
							(mid -0.137521 -0.162921)
							(end -0.1016 -0.1778)
						)
						(arc
							(start 0.1016 -0.1778)
							(mid 0.137521 -0.162921)
							(end 0.1524 -0.127)
						)
					)
					(width 0)
					(fill yes)
				)
			)
		)
		(pad "2" smd custom
			(at 0 0.2794 270)
			(size 0.0762 0.0762)
			(layers "B.Cu" "B.Mask" "B.Paste")
			(net "GND")
			(options
				(clearance outline)
				(anchor circle)
			)
			(primitives
				(gr_poly
					(pts
						(arc
							(start 0.1524 0.127)
							(mid 0.137521 0.162921)
							(end 0.1016 0.1778)
						)
						(arc
							(start -0.1016 0.1778)
							(mid -0.137521 0.162921)
							(end -0.1524 0.127)
						)
						(arc
							(start -0.1524 -0.127)
							(mid -0.137521 -0.162921)
							(end -0.1016 -0.1778)
						)
						(arc
							(start 0.1016 -0.1778)
							(mid 0.137521 -0.162921)
							(end 0.1524 -0.127)
						)
					)
					(width 0)
					(fill yes)
				)
			)
		)
	)
	(footprint ""
		(layer "B.Cu")
		(at 123.665742 -88.558624 180)
		(property "Reference" "R156"
			(at 0 0 0)
			(layer "B.SilkS")
			(hide yes)
			(effects
				(font
					(size 1.27 1.27)
				)
				(justify mirror)
			)
		)
		(property "Value" "0R2J-2-GP"
			(at -0.064008 -3.993896 180)
			(unlocked yes)
			(layer "B.Fab")
			(hide yes)
			(effects
				(font
					(size 1.016 1.016)
					(thickness 0.1524)
				)
				(justify mirror)
			)
		)
		(property "Device Type" "R402H16"
			(at -0.064008 -5.517896 180)
			(unlocked yes)
			(layer "B.Fab")
			(hide yes)
			(effects
				(font
					(size 1.016 1.016)
					(thickness 0.1524)
				)
				(justify mirror)
			)
		)
		(duplicate_pad_numbers_are_jumpers no)
		(fp_line
			(start 0.508 -0.9398)
			(end 0.508 0.9398)
			(stroke
				(width 0.1524)
				(type default)
			)
			(layer "B.SilkS")
		)
		(fp_line
			(start -0.508 -0.9398)
			(end 0.508 -0.9398)
			(stroke
				(width 0.1524)
				(type default)
			)
			(layer "B.SilkS")
		)
		(fp_rect
			(start 0.508 0.9398)
			(end -0.508 -0.9398)
			(stroke
				(width 0)
				(type default)
			)
			(fill no)
			(layer "B.CrtYd")
		)
		(fp_rect
			(start 0.508 0.9398)
			(end -0.508 -0.9398)
			(stroke
				(width 0)
				(type default)
			)
			(fill no)
			(layer "B.Fab")
		)
		(pad "1" smd custom
			(at 0 -0.4445)
			(size 0.1397 0.1397)
			(layers "B.Cu" "B.Mask" "B.Paste")
			(net "BMC_EXP_SPARE_0_R_LS")
			(options
				(clearance outline)
				(anchor circle)
			)
			(primitives
				(gr_poly
					(pts
						(arc
							(start -0.1778 0.2794)
							(mid -0.249642 0.249642)
							(end -0.2794 0.1778)
						)
						(arc
							(start -0.2794 -0.1778)
							(mid -0.249642 -0.249642)
							(end -0.1778 -0.2794)
						)
						(arc
							(start 0.1778 -0.2794)
							(mid 0.249642 -0.249642)
							(end 0.2794 -0.1778)
						)
						(arc
							(start 0.2794 0.1778)
							(mid 0.249642 0.249642)
							(end 0.1778 0.2794)
						)
					)
					(width 0)
					(fill yes)
				)
			)
		)
		(pad "2" smd custom
			(at 0 0.4445)
			(size 0.1397 0.1397)
			(layers "B.Cu" "B.Mask" "B.Paste")
			(net "BMC_SPARE_0_LS")
			(options
				(clearance outline)
				(anchor circle)
			)
			(primitives
				(gr_poly
					(pts
						(arc
							(start -0.1778 0.2794)
							(mid -0.249642 0.249642)
							(end -0.2794 0.1778)
						)
						(arc
							(start -0.2794 -0.1778)
							(mid -0.249642 -0.249642)
							(end -0.1778 -0.2794)
						)
						(arc
							(start 0.1778 -0.2794)
							(mid 0.249642 -0.249642)
							(end 0.2794 -0.1778)
						)
						(arc
							(start 0.2794 0.1778)
							(mid 0.249642 0.249642)
							(end 0.1778 0.2794)
						)
					)
					(width 0)
					(fill yes)
				)
			)
		)
	)
)
